# TIMECARD (Time Appliance Project (Time Card)) — schematic netlist excerpt (pin names and nets, part order shuffled) for the footprints in the layout excerpt that follows; sources: Cadence DE-HDL packaged netlist, KiCad conversion of R4006-B0001-02_R01.brd

C233  CAPACITOR  0.1UF 10V 10%  pkg SMC_0402R_H022  page 31 : \1\ = XP3R3V ; \2\ = SG
R393  RESISTOR  33OHM 1%  pkg SMC_0402R_H016  page 26 : \1\ = SMA3_LED_RED_N ; \2\ = UNNAMED_14_LED4PV14_I267_3

(kicad_pcb
	(version 20260206)
	(generator "pcbnew")
	(generator_version "10.0")
	(general
		(thickness 1.6)
		(legacy_teardrops no)
	)
	(paper "A4")
	(title_block
		(title "timecard-production-celestica-r4006 — R4006-B0001-02_R01.brd")
		(comment 1 "Time Appliance Project (Time Card) / footprints 399-400 of 1113")
	)
	(layers
		(0 "F.Cu" signal "TOP")
		(4 "In1.Cu" signal "L02_GND1")
		(6 "In2.Cu" signal "L03_SIG1")
		(8 "In3.Cu" signal "L04_GND2")
		(10 "In4.Cu" signal "L05_VCC1")
		(12 "In5.Cu" signal "L06_VCC2")
		(14 "In6.Cu" signal "L07_GND3")
		(16 "In7.Cu" signal "L08_SIG2")
		(18 "In8.Cu" signal "L09_GND4")
		(2 "B.Cu" signal "BOTTOM")
		(9 "F.Adhes" user "F.Adhesive")
		(11 "B.Adhes" user "B.Adhesive")
		(13 "F.Paste" user "Package Geometry/Pastemask Top")
		(15 "B.Paste" user "Package Geometry/Pastemask Bottom")
		(5 "F.SilkS" user "Ref Des/Silkscreen Top")
		(7 "B.SilkS" user "Ref Des/Silkscreen Bottom")
		(1 "F.Mask" user "Board Geometry/Soldermask Top")
		(3 "B.Mask" user "Board Geometry/Soldermask Bottom")
		(17 "Dwgs.User" user "User.Drawings")
		(19 "Cmts.User" user "User.Comments")
		(21 "Eco1.User" user "User.Eco1")
		(23 "Eco2.User" user "User.Eco2")
		(25 "Edge.Cuts" user "Board Geometry/Outline")
		(27 "Margin" user)
		(31 "F.CrtYd" user "Package Geometry/Place Bound Top")
		(29 "B.CrtYd" user "Package Geometry/Place Bound Bottom")
		(35 "F.Fab" user "Ref Des/Assembly Top")
		(33 "B.Fab" user "Ref Des/Assembly Bottom")
	)
	(footprint ""
		(layer "F.Cu")
		(at 111.506 -69.088 -90)
		(property "Reference" "C233"
			(at 0.254 -3.34137 90)
			(unlocked yes)
			(layer "F.SilkS")
			(effects
				(font
					(size 0.7874 0.5842)
					(thickness 0.1524)
				)
			)
		)
		(property "Value" "VAL*"
			(at 0.0762 2.067306 270)
			(unlocked yes)
			(layer "F.Fab")
			(hide yes)
			(effects
				(font
					(size 0.7874 0.5842)
					(thickness 0.1524)
				)
			)
		)
		(property "Tolerance" "TOL*"
			(at 0.0762 3.032506 270)
			(unlocked yes)
			(layer "Cmts.User")
			(hide yes)
			(effects
				(font
					(size 0.7874 0.5842)
					(thickness 0.1524)
				)
			)
		)
		(property "User Part Number" "PARTNUM*"
			(at 0.1016 4.023106 270)
			(unlocked yes)
			(layer "Cmts.User")
			(hide yes)
			(effects
				(font
					(size 0.7874 0.5842)
					(thickness 0.1524)
				)
			)
		)
		(property "Device Type" "CAPACITOR-G105-0B104-CK,0.1UF,A"
			(at 0.0508 1.127506 270)
			(unlocked yes)
			(layer "F.Fab")
			(hide yes)
			(effects
				(font
					(size 0.7874 0.5842)
					(thickness 0.1524)
				)
			)
		)
		(duplicate_pad_numbers_are_jumpers no)
		(fp_line
			(start -1.143 0.5588)
			(end 1.143 0.5588)
			(stroke
				(width 0.1)
				(type default)
			)
			(layer "F.SilkS")
		)
		(fp_line
			(start 1.143 0.5588)
			(end 1.143 -0.5588)
			(stroke
				(width 0.1)
				(type default)
			)
			(layer "F.SilkS")
		)
		(fp_line
			(start -1.143 -0.5588)
			(end -1.143 0.5588)
			(stroke
				(width 0.1)
				(type default)
			)
			(layer "F.SilkS")
		)
		(fp_line
			(start 1.143 -0.5588)
			(end -1.143 -0.5588)
			(stroke
				(width 0.1)
				(type default)
			)
			(layer "F.SilkS")
		)
		(fp_rect
			(start 1.143 -0.5588)
			(end -1.143 0.5588)
			(stroke
				(width 0)
				(type default)
			)
			(fill no)
			(layer "F.CrtYd")
		)
		(fp_line
			(start -0.508 0.3048)
			(end 0.508 0.3048)
			(stroke
				(width 0.1)
				(type default)
			)
			(layer "F.Fab")
		)
		(fp_line
			(start 0.508 0.3048)
			(end 0.508 -0.3048)
			(stroke
				(width 0.1)
				(type default)
			)
			(layer "F.Fab")
		)
		(fp_line
			(start -0.508 -0.3048)
			(end -0.508 0.3048)
			(stroke
				(width 0.1)
				(type default)
			)
			(layer "F.Fab")
		)
		(fp_line
			(start 0.508 -0.3048)
			(end -0.508 -0.3048)
			(stroke
				(width 0.1)
				(type default)
			)
			(layer "F.Fab")
		)
		(pad "1" smd rect
			(at -0.5334 0 270)
			(size 0.7112 0.6096)
			(layers "F.Cu" "F.Mask" "F.Paste")
			(net "XP3R3V")
		)
		(pad "2" smd rect
			(at 0.5334 0 270)
			(size 0.7112 0.6096)
			(layers "F.Cu" "F.Mask" "F.Paste")
			(net "SG")
		)
		(zone
			(layer "F.Cu")
			(hatch none 0.5)
			(connect_pads
				(clearance 0)
			)
			(min_thickness 0.25)
			(keepout
				(tracks allowed)
				(vias not_allowed)
				(pads allowed)
				(copperpour not_allowed)
				(footprints allowed)
			)
			(placement
				(enabled no)
				(sheetname "")
			)
			(fill
				(thermal_gap 0.5)
				(thermal_bridge_width 0.5)
				(island_removal_mode 0)
			)
			(polygon
				(pts
					(xy 111.8108 -69.0118) (xy 111.8108 -69.1642) (xy 111.2012 -69.1642) (xy 111.2012 -69.0118)
				)
			)
		)
	)
	(footprint ""
		(layer "F.Cu")
		(at 8.4328 -68.201032 90)
		(property "Reference" "R393"
			(at 3.553968 -0.51943 90)
			(unlocked yes)
			(layer "F.SilkS")
			(effects
				(font
					(size 0.7874 0.5842)
					(thickness 0.1524)
				)
			)
		)
		(property "Value" "VAL*"
			(at 0.02032 2.13233 90)
			(unlocked yes)
			(layer "F.Fab")
			(hide yes)
			(effects
				(font
					(size 0.7874 0.5842)
					(thickness 0.1524)
				)
			)
		)
		(property "Tolerance" "TOL*"
			(at 0.044704 3.05435 90)
			(unlocked yes)
			(layer "Cmts.User")
			(hide yes)
			(effects
				(font
					(size 0.7874 0.5842)
					(thickness 0.1524)
				)
			)
		)
		(property "User Part Number" "PARTNUM*"
			(at 0.02032 4.024884 90)
			(unlocked yes)
			(layer "Cmts.User")
			(hide yes)
			(effects
				(font
					(size 0.7874 0.5842)
					(thickness 0.1524)
				)
			)
		)
		(property "Device Type" "RESISTOR-G155-133R0-01,33OHM,1%"
			(at 0.008382 1.210564 90)
			(unlocked yes)
			(layer "F.Fab")
			(hide yes)
			(effects
				(font
					(size 0.7874 0.5842)
					(thickness 0.1524)
				)
			)
		)
		(duplicate_pad_numbers_are_jumpers no)
		(fp_line
			(start 1.143 -0.5588)
			(end -1.143 -0.5588)
			(stroke
				(width 0.1)
				(type default)
			)
			(layer "F.SilkS")
		)
		(fp_line
			(start -1.143 -0.5588)
			(end -1.143 0.5588)
			(stroke
				(width 0.1)
				(type default)
			)
			(layer "F.SilkS")
		)
		(fp_line
			(start 1.143 0.5588)
			(end 1.143 -0.5588)
			(stroke
				(width 0.1)
				(type default)
			)
			(layer "F.SilkS")
		)
		(fp_line
			(start -1.143 0.5588)
			(end 1.143 0.5588)
			(stroke
				(width 0.1)
				(type default)
			)
			(layer "F.SilkS")
		)
		(fp_rect
			(start -1.143 -0.5588)
			(end 1.143 0.5588)
			(stroke
				(width 0)
				(type default)
			)
			(fill no)
			(layer "F.CrtYd")
		)
		(fp_line
			(start 0.508 -0.3048)
			(end -0.508 -0.3048)
			(stroke
				(width 0.1)
				(type default)
			)
			(layer "F.Fab")
		)
		(fp_line
			(start -0.508 -0.3048)
			(end -0.508 0.3048)
			(stroke
				(width 0.1)
				(type default)
			)
			(layer "F.Fab")
		)
		(fp_line
			(start 0.508 0.3048)
			(end 0.508 -0.3048)
			(stroke
				(width 0.1)
				(type default)
			)
			(layer "F.Fab")
		)
		(fp_line
			(start -0.508 0.3048)
			(end 0.508 0.3048)
			(stroke
				(width 0.1)
				(type default)
			)
			(layer "F.Fab")
		)
		(pad "1" smd rect
			(at -0.5334 0 90)
			(size 0.7112 0.6096)
			(layers "F.Cu" "F.Mask" "F.Paste")
			(net "SMA3_LED_RED_N")
		)
		(pad "2" smd rect
			(at 0.5334 0 90)
			(size 0.7112 0.6096)
			(layers "F.Cu" "F.Mask" "F.Paste")
			(net "UNNAMED_14_LED4PV14_I267_3")
		)
		(zone
			(layer "F.Cu")
			(hatch none 0.5)
			(connect_pads
				(clearance 0)
			)
			(min_thickness 0.25)
			(keepout
				(tracks not_allowed)
				(vias allowed)
				(pads allowed)
				(copperpour not_allowed)
				(footprints allowed)
			)
			(placement
				(enabled no)
				(sheetname "")
			)
			(fill
				(thermal_gap 0.5)
				(thermal_bridge_width 0.5)
				(island_removal_mode 0)
			)
			(polygon
				(pts
					(xy 8.128 -68.124832) (xy 8.7376 -68.124832) (xy 8.7376 -68.277232) (xy 8.128 -68.277232)
				)
			)
		)
		(zone
			(layer "F.Cu")
			(hatch none 0.5)
			(connect_pads
				(clearance 0)
			)
			(min_thickness 0.25)
			(keepout
				(tracks allowed)
				(vias not_allowed)
				(pads allowed)
				(copperpour not_allowed)
				(footprints allowed)
			)
			(placement
				(enabled no)
				(sheetname "")
			)
			(fill
				(thermal_gap 0.5)
				(thermal_bridge_width 0.5)
				(island_removal_mode 0)
			)
			(polygon
				(pts
					(xy 8.128 -68.124832) (xy 8.7376 -68.124832) (xy 8.7376 -68.277232) (xy 8.128 -68.277232)
				)
			)
		)
	)
)
